FILE_TYPE = MACRO_DRAWING;
SET COLOR_WIRE YELLOW;
SET COLOR_PROP ORANGE;
SET COLOR_DOT WHITE;
SET COLOR_ARC YELLOW;
SET COLOR_BODY GREEN;
SET COLOR_NOTE PURPLE;
SET PROP_DISPLAY VALUE;
SET PAGE_NUMBER P458;
FORCEADD PT5161LRS..8
(-7825 3925);
FORCEPROP 1 LAST LOCATION U6017
J 0
(-8175 5550);
DISPLAY 0.723404 (-8175 5550);
PAINT GREEN (-8175 5550);
FORCEPROP 0 LAST $SEC 8
J 0
(-8175 5700);
DISPLAY 0.680851 (-8175 5700);
PAINT MONO (-8175 5700);
DISPLAY INVISIBLE (-8175 5700);
FORCEPROP 0 LAST CDS_SEC 8
J 0
(-8175 5700);
DISPLAY 0.680851 (-8175 5700);
DISPLAY INVISIBLE (-8175 5700);
FORCEPROP 0 LASTPIN (-7375 5075) $PN R35
J 0
(-7365 5085);
DISPLAY 0.680851 (-7365 5085);
PAINT MONO (-7365 5085);
FORCEPROP 0 LASTPIN (-7375 4725) $PN AB35
J 0
(-7365 4735);
DISPLAY 0.680851 (-7365 4735);
PAINT MONO (-7365 4735);
FORCEPROP 0 LASTPIN (-7375 4375) $PN AJ35
J 0
(-7365 4385);
DISPLAY 0.680851 (-7365 4385);
PAINT MONO (-7365 4385);
FORCEPROP 0 LASTPIN (-7375 4025) $PN AT35
J 0
(-7365 4035);
DISPLAY 0.680851 (-7365 4035);
PAINT MONO (-7365 4035);
FORCEPROP 0 LASTPIN (-7375 3675) $PN BC35
J 0
(-7365 3685);
DISPLAY 0.680851 (-7365 3685);
PAINT MONO (-7365 3685);
FORCEPROP 0 LASTPIN (-7375 3325) $PN BK35
J 0
(-7365 3335);
DISPLAY 0.680851 (-7365 3335);
PAINT MONO (-7365 3335);
FORCEPROP 0 LASTPIN (-7375 2975) $PN BU35
J 0
(-7365 2985);
DISPLAY 0.680851 (-7365 2985);
PAINT MONO (-7365 2985);
FORCEPROP 0 LASTPIN (-7375 2625) $PN CD35
J 0
(-7365 2635);
DISPLAY 0.680851 (-7365 2635);
PAINT MONO (-7365 2635);
FORCEPROP 0 LASTPIN (-7375 5175) $PN N34
J 0
(-7365 5185);
DISPLAY 0.680851 (-7365 5185);
PAINT MONO (-7365 5185);
FORCEPROP 0 LASTPIN (-7375 4825) $PN Y34
J 0
(-7365 4835);
DISPLAY 0.680851 (-7365 4835);
PAINT MONO (-7365 4835);
FORCEPROP 0 LASTPIN (-7375 4475) $PN AG34
J 0
(-7365 4485);
DISPLAY 0.680851 (-7365 4485);
PAINT MONO (-7365 4485);
FORCEPROP 0 LASTPIN (-7375 4125) $PN AP34
J 0
(-7365 4135);
DISPLAY 0.680851 (-7365 4135);
PAINT MONO (-7365 4135);
FORCEPROP 0 LASTPIN (-7375 3775) $PN BA34
J 0
(-7365 3785);
DISPLAY 0.680851 (-7365 3785);
PAINT MONO (-7365 3785);
FORCEPROP 0 LASTPIN (-7375 3425) $PN BH34
J 0
(-7365 3435);
DISPLAY 0.680851 (-7365 3435);
PAINT MONO (-7365 3435);
FORCEPROP 0 LASTPIN (-7375 3075) $PN BR34
J 0
(-7365 3085);
DISPLAY 0.680851 (-7365 3085);
PAINT MONO (-7365 3085);
FORCEPROP 0 LASTPIN (-7375 2725) $PN CB34
J 0
(-7365 2735);
DISPLAY 0.680851 (-7365 2735);
PAINT MONO (-7365 2735);
FORCEPROP 1 LAST MATERIAL IC
J 0
(-8175 5400);
DISPLAY 0.723404 (-8175 5400);
PAINT GREEN (-8175 5400);
FORCEPROP 2 LAST VALUE PT5161LRS
J 0
(-8175 5600);
DISPLAY 0.680851 (-8175 5600);
FORCEPROP 2 LAST PART_TYPE SMLF
J 0
(-8175 5650);
DISPLAY 0.680851 (-8175 5650);
FORCEPROP 1 LAST NEEDS_NO_SIZE TRUE
J 0
(-7825 3925);
DISPLAY 0.723404 (-7825 3925);
PAINT GREEN (-7825 3925);
DISPLAY INVISIBLE (-7825 3925);
FORCEPROP 1 LAST CDS_LMAN_SYM_OUTLINE -350,1450,300,-1400
J 0
(-7825 3925);
DISPLAY 0.468085 (-7825 3925);
PAINT GREEN (-7825 3925);
DISPLAY INVISIBLE (-7825 3925);
FORCEPROP 2 LAST CDS_LIB pure_quanta
J 0
(-7825 3925);
DISPLAY INVISIBLE (-7825 3925);
FORCEPROP 1 LAST PATH I1
J 0
(-7825 3925);
DISPLAY 0.723404 (-7825 3925);
PAINT GREEN (-7825 3925);
DISPLAY INVISIBLE (-7825 3925);
FORCEPROP 1 LAST PART_NUMBER AJ051610U03
J 0
(-8175 5475);
DISPLAY 0.723404 (-8175 5475);
PAINT GREEN (-8175 5475);
DISPLAY INVISIBLE (-8175 5475);
FORCEADD TAP..1
(-6800 4125);
FORCEPROP 3 LASTPIN (-6850 4125) SIG_NAME P5E_CPU1_P3_TX_C_DN<12>
J 0
(-6840 4135);
DISPLAY 0.659574 (-6840 4135);
PAINT MONO (-6840 4135);
DISPLAY INVISIBLE (-6840 4135);
FORCEPROP 1 LASTPIN (-6850 4125) BN 12
J 0
(-6862 4133);
DISPLAY 0.680851 (-6862 4133);
PAINT GREEN (-6862 4133);
FORCEPROP 2 LAST CDS_LIB standard
J 0
(-6800 4125);
DISPLAY INVISIBLE (-6800 4125);
FORCEPROP 1 LAST BODY_TYPE PLUMBING
J 0
(-6800 4175);
DISPLAY 0.872340 (-6800 4175);
PAINT GREEN (-6800 4175);
DISPLAY INVISIBLE (-6800 4175);
FORCEPROP 1 LAST HDL_TAP TRUE
J 0
(-6475 4000);
DISPLAY 0.872340 (-6475 4000);
DISPLAY INVISIBLE (-6475 4000);
FORCEPROP 1 LAST PATH I10
J 0
(-6802 4125);
DISPLAY 0.872340 (-6802 4125);
PAINT GREEN (-6802 4125);
DISPLAY INVISIBLE (-6802 4125);
FORCEADD TAP..1
(-6600 4025);
FORCEPROP 3 LASTPIN (-6650 4025) SIG_NAME P5E_CPU1_P3_TX_C_DP<12>
J 0
(-6640 4035);
DISPLAY 0.659574 (-6640 4035);
PAINT MONO (-6640 4035);
DISPLAY INVISIBLE (-6640 4035);
FORCEPROP 1 LASTPIN (-6650 4025) BN 12
J 0
(-6662 4033);
DISPLAY 0.680851 (-6662 4033);
PAINT GREEN (-6662 4033);
FORCEPROP 2 LAST CDS_LIB standard
J 0
(-6600 4025);
DISPLAY INVISIBLE (-6600 4025);
FORCEPROP 1 LAST BODY_TYPE PLUMBING
J 0
(-6600 4075);
DISPLAY 0.872340 (-6600 4075);
PAINT GREEN (-6600 4075);
DISPLAY INVISIBLE (-6600 4075);
FORCEPROP 1 LAST HDL_TAP TRUE
J 0
(-6275 3900);
DISPLAY 0.872340 (-6275 3900);
DISPLAY INVISIBLE (-6275 3900);
FORCEPROP 1 LAST PATH I11
J 0
(-6602 4025);
DISPLAY 0.872340 (-6602 4025);
PAINT GREEN (-6602 4025);
DISPLAY INVISIBLE (-6602 4025);
FORCEADD TAP..1
(-6800 4475);
FORCEPROP 3 LASTPIN (-6850 4475) SIG_NAME P5E_CPU1_P3_TX_C_DN<13>
J 0
(-6840 4485);
DISPLAY 0.659574 (-6840 4485);
PAINT MONO (-6840 4485);
DISPLAY INVISIBLE (-6840 4485);
FORCEPROP 1 LASTPIN (-6850 4475) BN 13
J 0
(-6862 4483);
DISPLAY 0.680851 (-6862 4483);
PAINT GREEN (-6862 4483);
FORCEPROP 2 LAST CDS_LIB standard
J 0
(-6800 4475);
DISPLAY INVISIBLE (-6800 4475);
FORCEPROP 1 LAST BODY_TYPE PLUMBING
J 0
(-6800 4525);
DISPLAY 0.872340 (-6800 4525);
PAINT GREEN (-6800 4525);
DISPLAY INVISIBLE (-6800 4525);
FORCEPROP 1 LAST HDL_TAP TRUE
J 0
(-6475 4350);
DISPLAY 0.872340 (-6475 4350);
DISPLAY INVISIBLE (-6475 4350);
FORCEPROP 1 LAST PATH I12
J 0
(-6802 4475);
DISPLAY 0.872340 (-6802 4475);
PAINT GREEN (-6802 4475);
DISPLAY INVISIBLE (-6802 4475);
FORCEADD TAP..1
(-6600 4375);
FORCEPROP 3 LASTPIN (-6650 4375) SIG_NAME P5E_CPU1_P3_TX_C_DP<13>
J 0
(-6640 4385);
DISPLAY 0.659574 (-6640 4385);
PAINT MONO (-6640 4385);
DISPLAY INVISIBLE (-6640 4385);
FORCEPROP 1 LASTPIN (-6650 4375) BN 13
J 0
(-6662 4383);
DISPLAY 0.680851 (-6662 4383);
PAINT GREEN (-6662 4383);
FORCEPROP 2 LAST CDS_LIB standard
J 0
(-6600 4375);
DISPLAY INVISIBLE (-6600 4375);
FORCEPROP 1 LAST BODY_TYPE PLUMBING
J 0
(-6600 4425);
DISPLAY 0.872340 (-6600 4425);
PAINT GREEN (-6600 4425);
DISPLAY INVISIBLE (-6600 4425);
FORCEPROP 1 LAST HDL_TAP TRUE
J 0
(-6275 4250);
DISPLAY 0.872340 (-6275 4250);
DISPLAY INVISIBLE (-6275 4250);
FORCEPROP 1 LAST PATH I13
J 0
(-6602 4375);
DISPLAY 0.872340 (-6602 4375);
PAINT GREEN (-6602 4375);
DISPLAY INVISIBLE (-6602 4375);
FORCEADD TAP..1
(-6600 4825);
FORCEPROP 3 LASTPIN (-6650 4825) SIG_NAME P5E_CPU1_P3_TX_C_DP<14>
J 0
(-6640 4835);
DISPLAY 0.659574 (-6640 4835);
PAINT MONO (-6640 4835);
DISPLAY INVISIBLE (-6640 4835);
FORCEPROP 1 LASTPIN (-6650 4825) BN 14
J 0
(-6662 4833);
DISPLAY 0.680851 (-6662 4833);
PAINT GREEN (-6662 4833);
FORCEPROP 2 LAST CDS_LIB standard
J 0
(-6600 4825);
DISPLAY INVISIBLE (-6600 4825);
FORCEPROP 1 LAST BODY_TYPE PLUMBING
J 0
(-6600 4875);
DISPLAY 0.872340 (-6600 4875);
PAINT GREEN (-6600 4875);
DISPLAY INVISIBLE (-6600 4875);
FORCEPROP 1 LAST HDL_TAP TRUE
J 0
(-6275 4700);
DISPLAY 0.872340 (-6275 4700);
DISPLAY INVISIBLE (-6275 4700);
FORCEPROP 1 LAST PATH I14
J 0
(-6602 4825);
DISPLAY 0.872340 (-6602 4825);
PAINT GREEN (-6602 4825);
DISPLAY INVISIBLE (-6602 4825);
FORCEADD TAP..1
(-6800 4725);
FORCEPROP 3 LASTPIN (-6850 4725) SIG_NAME P5E_CPU1_P3_TX_C_DN<14>
J 0
(-6840 4735);
DISPLAY 0.659574 (-6840 4735);
PAINT MONO (-6840 4735);
DISPLAY INVISIBLE (-6840 4735);
FORCEPROP 1 LASTPIN (-6850 4725) BN 14
J 0
(-6862 4733);
DISPLAY 0.680851 (-6862 4733);
PAINT GREEN (-6862 4733);
FORCEPROP 2 LAST CDS_LIB standard
J 0
(-6800 4725);
DISPLAY INVISIBLE (-6800 4725);
FORCEPROP 1 LAST BODY_TYPE PLUMBING
J 0
(-6800 4775);
DISPLAY 0.872340 (-6800 4775);
PAINT GREEN (-6800 4775);
DISPLAY INVISIBLE (-6800 4775);
FORCEPROP 1 LAST HDL_TAP TRUE
J 0
(-6475 4600);
DISPLAY 0.872340 (-6475 4600);
DISPLAY INVISIBLE (-6475 4600);
FORCEPROP 1 LAST PATH I15
J 0
(-6802 4725);
DISPLAY 0.872340 (-6802 4725);
PAINT GREEN (-6802 4725);
DISPLAY INVISIBLE (-6802 4725);
FORCEADD TAP..1
(-6800 5175);
FORCEPROP 3 LASTPIN (-6850 5175) SIG_NAME P5E_CPU1_P3_TX_C_DN<15>
J 0
(-6840 5185);
DISPLAY 0.659574 (-6840 5185);
PAINT MONO (-6840 5185);
DISPLAY INVISIBLE (-6840 5185);
FORCEPROP 1 LASTPIN (-6850 5175) BN 15
J 0
(-6862 5183);
DISPLAY 0.680851 (-6862 5183);
PAINT GREEN (-6862 5183);
FORCEPROP 2 LAST CDS_LIB standard
J 0
(-6800 5175);
DISPLAY INVISIBLE (-6800 5175);
FORCEPROP 1 LAST BODY_TYPE PLUMBING
J 0
(-6800 5225);
DISPLAY 0.872340 (-6800 5225);
PAINT GREEN (-6800 5225);
DISPLAY INVISIBLE (-6800 5225);
FORCEPROP 1 LAST HDL_TAP TRUE
J 0
(-6475 5050);
DISPLAY 0.872340 (-6475 5050);
DISPLAY INVISIBLE (-6475 5050);
FORCEPROP 1 LAST PATH I16
J 0
(-6802 5175);
DISPLAY 0.872340 (-6802 5175);
PAINT GREEN (-6802 5175);
DISPLAY INVISIBLE (-6802 5175);
FORCEADD TAP..1
(-6600 5075);
FORCEPROP 3 LASTPIN (-6650 5075) SIG_NAME P5E_CPU1_P3_TX_C_DP<15>
J 0
(-6640 5085);
DISPLAY 0.659574 (-6640 5085);
PAINT MONO (-6640 5085);
DISPLAY INVISIBLE (-6640 5085);
FORCEPROP 1 LASTPIN (-6650 5075) BN 15
J 0
(-6662 5083);
DISPLAY 0.680851 (-6662 5083);
PAINT GREEN (-6662 5083);
FORCEPROP 2 LAST CDS_LIB standard
J 0
(-6600 5075);
DISPLAY INVISIBLE (-6600 5075);
FORCEPROP 1 LAST BODY_TYPE PLUMBING
J 0
(-6600 5125);
DISPLAY 0.872340 (-6600 5125);
PAINT GREEN (-6600 5125);
DISPLAY INVISIBLE (-6600 5125);
FORCEPROP 1 LAST HDL_TAP TRUE
J 0
(-6275 4950);
DISPLAY 0.872340 (-6275 4950);
DISPLAY INVISIBLE (-6275 4950);
FORCEPROP 1 LAST PATH I17
J 0
(-6602 5075);
DISPLAY 0.872340 (-6602 5075);
PAINT GREEN (-6602 5075);
DISPLAY INVISIBLE (-6602 5075);
FORCEADD OFFPAGE..1
R 2
(-5600 5200);
FORCEPROP 2 LAST $XR0 67 
J 0
(-5414 5200);
DISPLAY 0.638298 (-5414 5200);
PAINT MONO (-5414 5200);
FORCEPROP 2 LAST CDS_LIB standard
J 2
(-5600 5200);
DISPLAY INVISIBLE (-5600 5200);
FORCEPROP 1 LAST OFFPAGE TRUE
J 2
(-5925 5075);
DISPLAY 0.872340 (-5925 5075);
DISPLAY INVISIBLE (-5925 5075);
FORCEPROP 1 LAST COMMENT_BODY TRUE
J 2
(-5725 5100);
DISPLAY 0.872340 (-5725 5100);
PAINT GREEN (-5725 5100);
DISPLAY INVISIBLE (-5725 5100);
FORCEPROP 2 LAST PATH I18
J 0
(-5425 5275);
DISPLAY 0.680851 (-5425 5275);
DISPLAY INVISIBLE (-5425 5275);
FORCEADD OFFPAGE..1
R 2
(-5600 5100);
FORCEPROP 2 LAST $XR0 67 
J 0
(-5414 5100);
DISPLAY 0.638298 (-5414 5100);
PAINT MONO (-5414 5100);
FORCEPROP 2 LAST CDS_LIB standard
J 0
(-5600 5100);
DISPLAY INVISIBLE (-5600 5100);
FORCEPROP 1 LAST OFFPAGE TRUE
J 2
(-5925 4975);
DISPLAY 0.872340 (-5925 4975);
DISPLAY INVISIBLE (-5925 4975);
FORCEPROP 1 LAST COMMENT_BODY TRUE
J 2
(-5725 5000);
DISPLAY 0.872340 (-5725 5000);
PAINT GREEN (-5725 5000);
DISPLAY INVISIBLE (-5725 5000);
FORCEPROP 2 LAST PATH I19
J 0
(-5425 5175);
DISPLAY 0.680851 (-5425 5175);
DISPLAY INVISIBLE (-5425 5175);
FORCEADD TAP..1
(-6600 2625);
FORCEPROP 3 LASTPIN (-6650 2625) SIG_NAME P5E_CPU1_P3_TX_C_DP<8>
J 0
(-6640 2635);
DISPLAY 0.659574 (-6640 2635);
PAINT MONO (-6640 2635);
DISPLAY INVISIBLE (-6640 2635);
FORCEPROP 1 LASTPIN (-6650 2625) BN 8
J 0
(-6662 2633);
DISPLAY 0.680851 (-6662 2633);
PAINT GREEN (-6662 2633);
FORCEPROP 2 LAST CDS_LIB standard
J 0
(-6600 2625);
DISPLAY INVISIBLE (-6600 2625);
FORCEPROP 1 LAST BODY_TYPE PLUMBING
J 0
(-6600 2675);
DISPLAY 0.872340 (-6600 2675);
PAINT GREEN (-6600 2675);
DISPLAY INVISIBLE (-6600 2675);
FORCEPROP 1 LAST HDL_TAP TRUE
J 0
(-6275 2500);
DISPLAY 0.872340 (-6275 2500);
DISPLAY INVISIBLE (-6275 2500);
FORCEPROP 1 LAST PATH I2
J 0
(-6602 2625);
DISPLAY 0.872340 (-6602 2625);
PAINT GREEN (-6602 2625);
DISPLAY INVISIBLE (-6602 2625);
FORCEADD TAP..1
(-2175 2675);
FORCEPROP 3 LASTPIN (-2225 2675) SIG_NAME P5E_CPU1_P3_TX_C_DN<0>
J 0
(-2215 2685);
DISPLAY 0.659574 (-2215 2685);
PAINT MONO (-2215 2685);
DISPLAY INVISIBLE (-2215 2685);
FORCEPROP 1 LASTPIN (-2225 2675) BN 0
J 0
(-2237 2683);
DISPLAY 0.680851 (-2237 2683);
PAINT GREEN (-2237 2683);
FORCEPROP 2 LAST CDS_LIB standard
J 0
(-2175 2675);
DISPLAY INVISIBLE (-2175 2675);
FORCEPROP 1 LAST BODY_TYPE PLUMBING
J 0
(-2175 2725);
DISPLAY 0.872340 (-2175 2725);
PAINT GREEN (-2175 2725);
DISPLAY INVISIBLE (-2175 2725);
FORCEPROP 1 LAST HDL_TAP TRUE
J 0
(-1850 2550);
DISPLAY 0.872340 (-1850 2550);
DISPLAY INVISIBLE (-1850 2550);
FORCEPROP 1 LAST PATH I20
J 0
(-2177 2675);
DISPLAY 0.872340 (-2177 2675);
PAINT GREEN (-2177 2675);
DISPLAY INVISIBLE (-2177 2675);
FORCEADD TAP..1
(-1975 2575);
FORCEPROP 3 LASTPIN (-2025 2575) SIG_NAME P5E_CPU1_P3_TX_C_DP<0>
J 0
(-2015 2585);
DISPLAY 0.659574 (-2015 2585);
PAINT MONO (-2015 2585);
DISPLAY INVISIBLE (-2015 2585);
FORCEPROP 1 LASTPIN (-2025 2575) BN 0
J 0
(-2037 2583);
DISPLAY 0.680851 (-2037 2583);
PAINT GREEN (-2037 2583);
FORCEPROP 2 LAST CDS_LIB standard
J 0
(-1975 2575);
DISPLAY INVISIBLE (-1975 2575);
FORCEPROP 1 LAST BODY_TYPE PLUMBING
J 0
(-1975 2625);
DISPLAY 0.872340 (-1975 2625);
PAINT GREEN (-1975 2625);
DISPLAY INVISIBLE (-1975 2625);
FORCEPROP 1 LAST HDL_TAP TRUE
J 0
(-1650 2450);
DISPLAY 0.872340 (-1650 2450);
DISPLAY INVISIBLE (-1650 2450);
FORCEPROP 1 LAST PATH I21
J 0
(-1977 2575);
DISPLAY 0.872340 (-1977 2575);
PAINT GREEN (-1977 2575);
DISPLAY INVISIBLE (-1977 2575);
FORCEADD TAP..1
(-2175 2925);
FORCEPROP 3 LASTPIN (-2225 2925) SIG_NAME P5E_CPU1_P3_TX_C_DN<1>
J 0
(-2215 2935);
DISPLAY 0.659574 (-2215 2935);
PAINT MONO (-2215 2935);
DISPLAY INVISIBLE (-2215 2935);
FORCEPROP 1 LASTPIN (-2225 2925) BN 1
J 0
(-2237 2933);
DISPLAY 0.680851 (-2237 2933);
PAINT GREEN (-2237 2933);
FORCEPROP 2 LAST CDS_LIB standard
J 0
(-2175 2925);
DISPLAY INVISIBLE (-2175 2925);
FORCEPROP 1 LAST BODY_TYPE PLUMBING
J 0
(-2175 2975);
DISPLAY 0.872340 (-2175 2975);
PAINT GREEN (-2175 2975);
DISPLAY INVISIBLE (-2175 2975);
FORCEPROP 1 LAST HDL_TAP TRUE
J 0
(-1850 2800);
DISPLAY 0.872340 (-1850 2800);
DISPLAY INVISIBLE (-1850 2800);
FORCEPROP 1 LAST PATH I22
J 0
(-2177 2925);
DISPLAY 0.872340 (-2177 2925);
PAINT GREEN (-2177 2925);
DISPLAY INVISIBLE (-2177 2925);
FORCEADD TAP..1
(-1975 3025);
FORCEPROP 3 LASTPIN (-2025 3025) SIG_NAME P5E_CPU1_P3_TX_C_DP<1>
J 0
(-2015 3035);
DISPLAY 0.659574 (-2015 3035);
PAINT MONO (-2015 3035);
DISPLAY INVISIBLE (-2015 3035);
FORCEPROP 1 LASTPIN (-2025 3025) BN 1
J 0
(-2037 3033);
DISPLAY 0.680851 (-2037 3033);
PAINT GREEN (-2037 3033);
FORCEPROP 2 LAST CDS_LIB standard
J 0
(-1975 3025);
DISPLAY INVISIBLE (-1975 3025);
FORCEPROP 1 LAST BODY_TYPE PLUMBING
J 0
(-1975 3075);
DISPLAY 0.872340 (-1975 3075);
PAINT GREEN (-1975 3075);
DISPLAY INVISIBLE (-1975 3075);
FORCEPROP 1 LAST HDL_TAP TRUE
J 0
(-1650 2900);
DISPLAY 0.872340 (-1650 2900);
DISPLAY INVISIBLE (-1650 2900);
FORCEPROP 1 LAST PATH I23
J 0
(-1977 3025);
DISPLAY 0.872340 (-1977 3025);
PAINT GREEN (-1977 3025);
DISPLAY INVISIBLE (-1977 3025);
FORCEADD TAP..1
(-2175 3375);
FORCEPROP 3 LASTPIN (-2225 3375) SIG_NAME P5E_CPU1_P3_TX_C_DN<2>
J 0
(-2215 3385);
DISPLAY 0.659574 (-2215 3385);
PAINT MONO (-2215 3385);
DISPLAY INVISIBLE (-2215 3385);
FORCEPROP 1 LASTPIN (-2225 3375) BN 2
J 0
(-2237 3383);
DISPLAY 0.680851 (-2237 3383);
PAINT GREEN (-2237 3383);
FORCEPROP 2 LAST CDS_LIB standard
J 0
(-2175 3375);
DISPLAY INVISIBLE (-2175 3375);
FORCEPROP 1 LAST BODY_TYPE PLUMBING
J 0
(-2175 3425);
DISPLAY 0.872340 (-2175 3425);
PAINT GREEN (-2175 3425);
DISPLAY INVISIBLE (-2175 3425);
FORCEPROP 1 LAST HDL_TAP TRUE
J 0
(-1850 3250);
DISPLAY 0.872340 (-1850 3250);
DISPLAY INVISIBLE (-1850 3250);
FORCEPROP 1 LAST PATH I24
J 0
(-2177 3375);
DISPLAY 0.872340 (-2177 3375);
PAINT GREEN (-2177 3375);
DISPLAY INVISIBLE (-2177 3375);
FORCEADD TAP..1
(-1975 3275);
FORCEPROP 3 LASTPIN (-2025 3275) SIG_NAME P5E_CPU1_P3_TX_C_DP<2>
J 0
(-2015 3285);
DISPLAY 0.659574 (-2015 3285);
PAINT MONO (-2015 3285);
DISPLAY INVISIBLE (-2015 3285);
FORCEPROP 1 LASTPIN (-2025 3275) BN 2
J 0
(-2037 3283);
DISPLAY 0.680851 (-2037 3283);
PAINT GREEN (-2037 3283);
FORCEPROP 2 LAST CDS_LIB standard
J 0
(-1975 3275);
DISPLAY INVISIBLE (-1975 3275);
FORCEPROP 1 LAST BODY_TYPE PLUMBING
J 0
(-1975 3325);
DISPLAY 0.872340 (-1975 3325);
PAINT GREEN (-1975 3325);
DISPLAY INVISIBLE (-1975 3325);
FORCEPROP 1 LAST HDL_TAP TRUE
J 0
(-1650 3150);
DISPLAY 0.872340 (-1650 3150);
DISPLAY INVISIBLE (-1650 3150);
FORCEPROP 1 LAST PATH I25
J 0
(-1977 3275);
DISPLAY 0.872340 (-1977 3275);
PAINT GREEN (-1977 3275);
DISPLAY INVISIBLE (-1977 3275);
FORCEADD TAP..1
(-1975 3625);
FORCEPROP 3 LASTPIN (-2025 3625) SIG_NAME P5E_CPU1_P3_TX_C_DP<3>
J 0
(-2015 3635);
DISPLAY 0.659574 (-2015 3635);
PAINT MONO (-2015 3635);
DISPLAY INVISIBLE (-2015 3635);
FORCEPROP 1 LASTPIN (-2025 3625) BN 3
J 0
(-2037 3633);
DISPLAY 0.680851 (-2037 3633);
PAINT GREEN (-2037 3633);
FORCEPROP 2 LAST CDS_LIB standard
J 0
(-1975 3625);
DISPLAY INVISIBLE (-1975 3625);
FORCEPROP 1 LAST BODY_TYPE PLUMBING
J 0
(-1975 3675);
DISPLAY 0.872340 (-1975 3675);
PAINT GREEN (-1975 3675);
DISPLAY INVISIBLE (-1975 3675);
FORCEPROP 1 LAST HDL_TAP TRUE
J 0
(-1650 3500);
DISPLAY 0.872340 (-1650 3500);
DISPLAY INVISIBLE (-1650 3500);
FORCEPROP 1 LAST PATH I26
J 0
(-1977 3625);
DISPLAY 0.872340 (-1977 3625);
PAINT GREEN (-1977 3625);
DISPLAY INVISIBLE (-1977 3625);
FORCEADD TAP..1
(-2175 3725);
FORCEPROP 3 LASTPIN (-2225 3725) SIG_NAME P5E_CPU1_P3_TX_C_DN<3>
J 0
(-2215 3735);
DISPLAY 0.659574 (-2215 3735);
PAINT MONO (-2215 3735);
DISPLAY INVISIBLE (-2215 3735);
FORCEPROP 1 LASTPIN (-2225 3725) BN 3
J 0
(-2237 3733);
DISPLAY 0.680851 (-2237 3733);
PAINT GREEN (-2237 3733);
FORCEPROP 2 LAST CDS_LIB standard
J 0
(-2175 3725);
DISPLAY INVISIBLE (-2175 3725);
FORCEPROP 1 LAST BODY_TYPE PLUMBING
J 0
(-2175 3775);
DISPLAY 0.872340 (-2175 3775);
PAINT GREEN (-2175 3775);
DISPLAY INVISIBLE (-2175 3775);
FORCEPROP 1 LAST HDL_TAP TRUE
J 0
(-1850 3600);
DISPLAY 0.872340 (-1850 3600);
DISPLAY INVISIBLE (-1850 3600);
FORCEPROP 1 LAST PATH I27
J 0
(-2177 3725);
DISPLAY 0.872340 (-2177 3725);
PAINT GREEN (-2177 3725);
DISPLAY INVISIBLE (-2177 3725);
FORCEADD TAP..1
(-2175 4075);
FORCEPROP 3 LASTPIN (-2225 4075) SIG_NAME P5E_CPU1_P3_TX_C_DN<4>
J 0
(-2215 4085);
DISPLAY 0.659574 (-2215 4085);
PAINT MONO (-2215 4085);
DISPLAY INVISIBLE (-2215 4085);
FORCEPROP 1 LASTPIN (-2225 4075) BN 4
J 0
(-2237 4083);
DISPLAY 0.680851 (-2237 4083);
PAINT GREEN (-2237 4083);
FORCEPROP 2 LAST CDS_LIB standard
J 0
(-2175 4075);
DISPLAY INVISIBLE (-2175 4075);
FORCEPROP 1 LAST BODY_TYPE PLUMBING
J 0
(-2175 4125);
DISPLAY 0.872340 (-2175 4125);
PAINT GREEN (-2175 4125);
DISPLAY INVISIBLE (-2175 4125);
FORCEPROP 1 LAST HDL_TAP TRUE
J 0
(-1850 3950);
DISPLAY 0.872340 (-1850 3950);
DISPLAY INVISIBLE (-1850 3950);
FORCEPROP 1 LAST PATH I28
J 0
(-2177 4075);
DISPLAY 0.872340 (-2177 4075);
PAINT GREEN (-2177 4075);
DISPLAY INVISIBLE (-2177 4075);
FORCEADD TAP..1
(-1975 3975);
FORCEPROP 3 LASTPIN (-2025 3975) SIG_NAME P5E_CPU1_P3_TX_C_DP<4>
J 0
(-2015 3985);
DISPLAY 0.659574 (-2015 3985);
PAINT MONO (-2015 3985);
DISPLAY INVISIBLE (-2015 3985);
FORCEPROP 1 LASTPIN (-2025 3975) BN 4
J 0
(-2037 3983);
DISPLAY 0.680851 (-2037 3983);
PAINT GREEN (-2037 3983);
FORCEPROP 2 LAST CDS_LIB standard
J 0
(-1975 3975);
DISPLAY INVISIBLE (-1975 3975);
FORCEPROP 1 LAST BODY_TYPE PLUMBING
J 0
(-1975 4025);
DISPLAY 0.872340 (-1975 4025);
PAINT GREEN (-1975 4025);
DISPLAY INVISIBLE (-1975 4025);
FORCEPROP 1 LAST HDL_TAP TRUE
J 0
(-1650 3850);
DISPLAY 0.872340 (-1650 3850);
DISPLAY INVISIBLE (-1650 3850);
FORCEPROP 1 LAST PATH I29
J 0
(-1977 3975);
DISPLAY 0.872340 (-1977 3975);
PAINT GREEN (-1977 3975);
DISPLAY INVISIBLE (-1977 3975);
FORCEADD TAP..1
(-6800 2725);
FORCEPROP 3 LASTPIN (-6850 2725) SIG_NAME P5E_CPU1_P3_TX_C_DN<8>
J 0
(-6840 2735);
DISPLAY 0.659574 (-6840 2735);
PAINT MONO (-6840 2735);
DISPLAY INVISIBLE (-6840 2735);
FORCEPROP 1 LASTPIN (-6850 2725) BN 8
J 0
(-6862 2733);
DISPLAY 0.680851 (-6862 2733);
PAINT GREEN (-6862 2733);
FORCEPROP 2 LAST CDS_LIB standard
J 0
(-6800 2725);
DISPLAY INVISIBLE (-6800 2725);
FORCEPROP 1 LAST BODY_TYPE PLUMBING
J 0
(-6800 2775);
DISPLAY 0.872340 (-6800 2775);
PAINT GREEN (-6800 2775);
DISPLAY INVISIBLE (-6800 2775);
FORCEPROP 1 LAST HDL_TAP TRUE
J 0
(-6475 2600);
DISPLAY 0.872340 (-6475 2600);
DISPLAY INVISIBLE (-6475 2600);
FORCEPROP 1 LAST PATH I3
J 0
(-6802 2725);
DISPLAY 0.872340 (-6802 2725);
PAINT GREEN (-6802 2725);
DISPLAY INVISIBLE (-6802 2725);
FORCEADD TAP..1
(-2175 4425);
FORCEPROP 3 LASTPIN (-2225 4425) SIG_NAME P5E_CPU1_P3_TX_C_DN<5>
J 0
(-2215 4435);
DISPLAY 0.659574 (-2215 4435);
PAINT MONO (-2215 4435);
DISPLAY INVISIBLE (-2215 4435);
FORCEPROP 1 LASTPIN (-2225 4425) BN 5
J 0
(-2237 4433);
DISPLAY 0.680851 (-2237 4433);
PAINT GREEN (-2237 4433);
FORCEPROP 2 LAST CDS_LIB standard
J 0
(-2175 4425);
DISPLAY INVISIBLE (-2175 4425);
FORCEPROP 1 LAST BODY_TYPE PLUMBING
J 0
(-2175 4475);
DISPLAY 0.872340 (-2175 4475);
PAINT GREEN (-2175 4475);
DISPLAY INVISIBLE (-2175 4475);
FORCEPROP 1 LAST HDL_TAP TRUE
J 0
(-1850 4300);
DISPLAY 0.872340 (-1850 4300);
DISPLAY INVISIBLE (-1850 4300);
FORCEPROP 1 LAST PATH I30
J 0
(-2177 4425);
DISPLAY 0.872340 (-2177 4425);
PAINT GREEN (-2177 4425);
DISPLAY INVISIBLE (-2177 4425);
FORCEADD TAP..1
(-1975 4325);
FORCEPROP 3 LASTPIN (-2025 4325) SIG_NAME P5E_CPU1_P3_TX_C_DP<5>
J 0
(-2015 4335);
DISPLAY 0.659574 (-2015 4335);
PAINT MONO (-2015 4335);
DISPLAY INVISIBLE (-2015 4335);
FORCEPROP 1 LASTPIN (-2025 4325) BN 5
J 0
(-2037 4333);
DISPLAY 0.680851 (-2037 4333);
PAINT GREEN (-2037 4333);
FORCEPROP 2 LAST CDS_LIB standard
J 0
(-1975 4325);
DISPLAY INVISIBLE (-1975 4325);
FORCEPROP 1 LAST BODY_TYPE PLUMBING
J 0
(-1975 4375);
DISPLAY 0.872340 (-1975 4375);
PAINT GREEN (-1975 4375);
DISPLAY INVISIBLE (-1975 4375);
FORCEPROP 1 LAST HDL_TAP TRUE
J 0
(-1650 4200);
DISPLAY 0.872340 (-1650 4200);
DISPLAY INVISIBLE (-1650 4200);
FORCEPROP 1 LAST PATH I31
J 0
(-1977 4325);
DISPLAY 0.872340 (-1977 4325);
PAINT GREEN (-1977 4325);
DISPLAY INVISIBLE (-1977 4325);
FORCEADD TAP..1
(-1975 4675);
FORCEPROP 3 LASTPIN (-2025 4675) SIG_NAME P5E_CPU1_P3_TX_C_DP<6>
J 0
(-2015 4685);
DISPLAY 0.659574 (-2015 4685);
PAINT MONO (-2015 4685);
DISPLAY INVISIBLE (-2015 4685);
FORCEPROP 1 LASTPIN (-2025 4675) BN 6
J 0
(-2037 4683);
DISPLAY 0.680851 (-2037 4683);
PAINT GREEN (-2037 4683);
FORCEPROP 2 LAST CDS_LIB standard
J 0
(-1975 4675);
DISPLAY INVISIBLE (-1975 4675);
FORCEPROP 1 LAST BODY_TYPE PLUMBING
J 0
(-1975 4725);
DISPLAY 0.872340 (-1975 4725);
PAINT GREEN (-1975 4725);
DISPLAY INVISIBLE (-1975 4725);
FORCEPROP 1 LAST HDL_TAP TRUE
J 0
(-1650 4550);
DISPLAY 0.872340 (-1650 4550);
DISPLAY INVISIBLE (-1650 4550);
FORCEPROP 1 LAST PATH I32
J 0
(-1977 4675);
DISPLAY 0.872340 (-1977 4675);
PAINT GREEN (-1977 4675);
DISPLAY INVISIBLE (-1977 4675);
FORCEADD TAP..1
(-2175 4775);
FORCEPROP 3 LASTPIN (-2225 4775) SIG_NAME P5E_CPU1_P3_TX_C_DN<6>
J 0
(-2215 4785);
DISPLAY 0.659574 (-2215 4785);
PAINT MONO (-2215 4785);
DISPLAY INVISIBLE (-2215 4785);
FORCEPROP 1 LASTPIN (-2225 4775) BN 6
J 0
(-2237 4783);
DISPLAY 0.680851 (-2237 4783);
PAINT GREEN (-2237 4783);
FORCEPROP 2 LAST CDS_LIB standard
J 0
(-2175 4775);
DISPLAY INVISIBLE (-2175 4775);
FORCEPROP 1 LAST BODY_TYPE PLUMBING
J 0
(-2175 4825);
DISPLAY 0.872340 (-2175 4825);
PAINT GREEN (-2175 4825);
DISPLAY INVISIBLE (-2175 4825);
FORCEPROP 1 LAST HDL_TAP TRUE
J 0
(-1850 4650);
DISPLAY 0.872340 (-1850 4650);
DISPLAY INVISIBLE (-1850 4650);
FORCEPROP 1 LAST PATH I33
J 0
(-2177 4775);
DISPLAY 0.872340 (-2177 4775);
PAINT GREEN (-2177 4775);
DISPLAY INVISIBLE (-2177 4775);
FORCEADD TAP..1
(-2175 5125);
FORCEPROP 3 LASTPIN (-2225 5125) SIG_NAME P5E_CPU1_P3_TX_C_DN<7>
J 0
(-2215 5135);
DISPLAY 0.659574 (-2215 5135);
PAINT MONO (-2215 5135);
DISPLAY INVISIBLE (-2215 5135);
FORCEPROP 1 LASTPIN (-2225 5125) BN 7
J 0
(-2237 5133);
DISPLAY 0.680851 (-2237 5133);
PAINT GREEN (-2237 5133);
FORCEPROP 2 LAST CDS_LIB standard
J 0
(-2175 5125);
DISPLAY INVISIBLE (-2175 5125);
FORCEPROP 1 LAST BODY_TYPE PLUMBING
J 0
(-2175 5175);
DISPLAY 0.872340 (-2175 5175);
PAINT GREEN (-2175 5175);
DISPLAY INVISIBLE (-2175 5175);
FORCEPROP 1 LAST HDL_TAP TRUE
J 0
(-1850 5000);
DISPLAY 0.872340 (-1850 5000);
DISPLAY INVISIBLE (-1850 5000);
FORCEPROP 1 LAST PATH I34
J 0
(-2177 5125);
DISPLAY 0.872340 (-2177 5125);
PAINT GREEN (-2177 5125);
DISPLAY INVISIBLE (-2177 5125);
FORCEADD TAP..1
(-1975 5025);
FORCEPROP 3 LASTPIN (-2025 5025) SIG_NAME P5E_CPU1_P3_TX_C_DP<7>
J 0
(-2015 5035);
DISPLAY 0.659574 (-2015 5035);
PAINT MONO (-2015 5035);
DISPLAY INVISIBLE (-2015 5035);
FORCEPROP 1 LASTPIN (-2025 5025) BN 7
J 0
(-2037 5033);
DISPLAY 0.680851 (-2037 5033);
PAINT GREEN (-2037 5033);
FORCEPROP 2 LAST CDS_LIB standard
J 0
(-1975 5025);
DISPLAY INVISIBLE (-1975 5025);
FORCEPROP 1 LAST BODY_TYPE PLUMBING
J 0
(-1975 5075);
DISPLAY 0.872340 (-1975 5075);
PAINT GREEN (-1975 5075);
DISPLAY INVISIBLE (-1975 5075);
FORCEPROP 1 LAST HDL_TAP TRUE
J 0
(-1650 4900);
DISPLAY 0.872340 (-1650 4900);
DISPLAY INVISIBLE (-1650 4900);
FORCEPROP 1 LAST PATH I35
J 0
(-1977 5025);
DISPLAY 0.872340 (-1977 5025);
PAINT GREEN (-1977 5025);
DISPLAY INVISIBLE (-1977 5025);
FORCEADD OFFPAGE..1
R 2
(-975 5150);
FORCEPROP 2 LAST $XR0 67 
J 0
(-789 5150);
DISPLAY 0.638298 (-789 5150);
PAINT MONO (-789 5150);
FORCEPROP 2 LAST CDS_LIB standard
J 2
(-975 5150);
DISPLAY INVISIBLE (-975 5150);
FORCEPROP 1 LAST OFFPAGE TRUE
J 2
(-1300 5025);
DISPLAY 0.872340 (-1300 5025);
DISPLAY INVISIBLE (-1300 5025);
FORCEPROP 1 LAST COMMENT_BODY TRUE
J 2
(-1100 5050);
DISPLAY 0.872340 (-1100 5050);
PAINT GREEN (-1100 5050);
DISPLAY INVISIBLE (-1100 5050);
FORCEPROP 2 LAST PATH I36
J 0
(-800 5225);
DISPLAY 0.680851 (-800 5225);
DISPLAY INVISIBLE (-800 5225);
FORCEADD OFFPAGE..1
R 2
(-975 5050);
FORCEPROP 2 LAST $XR0 67 
J 0
(-789 5050);
DISPLAY 0.638298 (-789 5050);
PAINT MONO (-789 5050);
FORCEPROP 2 LAST CDS_LIB standard
J 0
(-975 5050);
DISPLAY INVISIBLE (-975 5050);
FORCEPROP 1 LAST OFFPAGE TRUE
J 2
(-1300 4925);
DISPLAY 0.872340 (-1300 4925);
DISPLAY INVISIBLE (-1300 4925);
FORCEPROP 1 LAST COMMENT_BODY TRUE
J 2
(-1100 4950);
DISPLAY 0.872340 (-1100 4950);
PAINT GREEN (-1100 4950);
DISPLAY INVISIBLE (-1100 4950);
FORCEPROP 2 LAST PATH I37
J 0
(-800 5125);
DISPLAY 0.680851 (-800 5125);
DISPLAY INVISIBLE (-800 5125);
FORCEADD PT5161LRS..9
(-3200 3875);
FORCEPROP 1 LAST LOCATION U6017
J 0
(-3550 5500);
DISPLAY 0.723404 (-3550 5500);
PAINT GREEN (-3550 5500);
FORCEPROP 0 LAST $SEC 9
J 0
(-3550 5650);
DISPLAY 0.680851 (-3550 5650);
PAINT MONO (-3550 5650);
DISPLAY INVISIBLE (-3550 5650);
FORCEPROP 0 LAST CDS_SEC 9
J 0
(-3550 5650);
DISPLAY 0.680851 (-3550 5650);
DISPLAY INVISIBLE (-3550 5650);
FORCEPROP 0 LASTPIN (-2750 5025) $PN CL35
J 0
(-2740 5035);
DISPLAY 0.680851 (-2740 5035);
PAINT MONO (-2740 5035);
FORCEPROP 0 LASTPIN (-2750 4675) $PN CV35
J 0
(-2740 4685);
DISPLAY 0.680851 (-2740 4685);
PAINT MONO (-2740 4685);
FORCEPROP 0 LASTPIN (-2750 4325) $PN DE35
J 0
(-2740 4335);
DISPLAY 0.680851 (-2740 4335);
PAINT MONO (-2740 4335);
FORCEPROP 0 LASTPIN (-2750 3975) $PN DM35
J 0
(-2740 3985);
DISPLAY 0.680851 (-2740 3985);
PAINT MONO (-2740 3985);
FORCEPROP 0 LASTPIN (-2750 3625) $PN DW35
J 0
(-2740 3635);
DISPLAY 0.680851 (-2740 3635);
PAINT MONO (-2740 3635);
FORCEPROP 0 LASTPIN (-2750 3275) $PN EF35
J 0
(-2740 3285);
DISPLAY 0.680851 (-2740 3285);
PAINT MONO (-2740 3285);
FORCEPROP 0 LASTPIN (-2750 2925) $PN EN35
J 0
(-2740 2935);
DISPLAY 0.680851 (-2740 2935);
PAINT MONO (-2740 2935);
FORCEPROP 0 LASTPIN (-2750 2575) $PN EY35
J 0
(-2740 2585);
DISPLAY 0.680851 (-2740 2585);
PAINT MONO (-2740 2585);
FORCEPROP 0 LASTPIN (-2750 5125) $PN CJ34
J 0
(-2740 5135);
DISPLAY 0.680851 (-2740 5135);
PAINT MONO (-2740 5135);
FORCEPROP 0 LASTPIN (-2750 4775) $PN CT34
J 0
(-2740 4785);
DISPLAY 0.680851 (-2740 4785);
PAINT MONO (-2740 4785);
FORCEPROP 0 LASTPIN (-2750 4425) $PN DC34
J 0
(-2740 4435);
DISPLAY 0.680851 (-2740 4435);
PAINT MONO (-2740 4435);
FORCEPROP 0 LASTPIN (-2750 4075) $PN DK34
J 0
(-2740 4085);
DISPLAY 0.680851 (-2740 4085);
PAINT MONO (-2740 4085);
FORCEPROP 0 LASTPIN (-2750 3725) $PN DU34
J 0
(-2740 3735);
DISPLAY 0.680851 (-2740 3735);
PAINT MONO (-2740 3735);
FORCEPROP 0 LASTPIN (-2750 3375) $PN ED34
J 0
(-2740 3385);
DISPLAY 0.680851 (-2740 3385);
PAINT MONO (-2740 3385);
FORCEPROP 0 LASTPIN (-2750 3025) $PN EL34
J 0
(-2740 3035);
DISPLAY 0.680851 (-2740 3035);
PAINT MONO (-2740 3035);
FORCEPROP 0 LASTPIN (-2750 2675) $PN EV34
J 0
(-2740 2685);
DISPLAY 0.680851 (-2740 2685);
PAINT MONO (-2740 2685);
FORCEPROP 2 LAST VALUE PT5161LRS
J 0
(-3550 5550);
DISPLAY 0.680851 (-3550 5550);
FORCEPROP 2 LAST PART_TYPE SMLF
J 0
(-3550 5600);
DISPLAY 0.680851 (-3550 5600);
FORCEPROP 1 LAST MATERIAL IC
J 0
(-3550 5350);
DISPLAY 0.723404 (-3550 5350);
PAINT GREEN (-3550 5350);
FORCEPROP 2 LAST CDS_LIB pure_quanta
J 0
(-3200 3875);
DISPLAY INVISIBLE (-3200 3875);
FORCEPROP 1 LAST CDS_LMAN_SYM_OUTLINE -350,1450,300,-1400
J 0
(-3200 3875);
DISPLAY 0.468085 (-3200 3875);
PAINT GREEN (-3200 3875);
DISPLAY INVISIBLE (-3200 3875);
FORCEPROP 1 LAST NEEDS_NO_SIZE TRUE
J 0
(-3200 3875);
DISPLAY 0.723404 (-3200 3875);
PAINT GREEN (-3200 3875);
DISPLAY INVISIBLE (-3200 3875);
FORCEPROP 1 LAST PATH I38
J 0
(-3200 3875);
DISPLAY 0.723404 (-3200 3875);
PAINT GREEN (-3200 3875);
DISPLAY INVISIBLE (-3200 3875);
FORCEPROP 1 LAST PART_NUMBER AJ051610U03
J 0
(-3550 5425);
DISPLAY 0.723404 (-3550 5425);
PAINT GREEN (-3550 5425);
DISPLAY INVISIBLE (-3550 5425);
FORCEADD TAP..1
(-6800 3075);
FORCEPROP 3 LASTPIN (-6850 3075) SIG_NAME P5E_CPU1_P3_TX_C_DN<9>
J 0
(-6840 3085);
DISPLAY 0.659574 (-6840 3085);
PAINT MONO (-6840 3085);
DISPLAY INVISIBLE (-6840 3085);
FORCEPROP 1 LASTPIN (-6850 3075) BN 9
J 0
(-6862 3083);
DISPLAY 0.680851 (-6862 3083);
PAINT GREEN (-6862 3083);
FORCEPROP 2 LAST CDS_LIB standard
J 0
(-6800 3075);
DISPLAY INVISIBLE (-6800 3075);
FORCEPROP 1 LAST BODY_TYPE PLUMBING
J 0
(-6800 3125);
DISPLAY 0.872340 (-6800 3125);
PAINT GREEN (-6800 3125);
DISPLAY INVISIBLE (-6800 3125);
FORCEPROP 1 LAST HDL_TAP TRUE
J 0
(-6475 2950);
DISPLAY 0.872340 (-6475 2950);
DISPLAY INVISIBLE (-6475 2950);
FORCEPROP 1 LAST PATH I4
J 0
(-6802 3075);
DISPLAY 0.872340 (-6802 3075);
PAINT GREEN (-6802 3075);
DISPLAY INVISIBLE (-6802 3075);
FORCEADD TAP..1
(-6600 2975);
FORCEPROP 3 LASTPIN (-6650 2975) SIG_NAME P5E_CPU1_P3_TX_C_DP<9>
J 0
(-6640 2985);
DISPLAY 0.659574 (-6640 2985);
PAINT MONO (-6640 2985);
DISPLAY INVISIBLE (-6640 2985);
FORCEPROP 1 LASTPIN (-6650 2975) BN 9
J 0
(-6662 2983);
DISPLAY 0.680851 (-6662 2983);
PAINT GREEN (-6662 2983);
FORCEPROP 2 LAST CDS_LIB standard
J 0
(-6600 2975);
DISPLAY INVISIBLE (-6600 2975);
FORCEPROP 1 LAST BODY_TYPE PLUMBING
J 0
(-6600 3025);
DISPLAY 0.872340 (-6600 3025);
PAINT GREEN (-6600 3025);
DISPLAY INVISIBLE (-6600 3025);
FORCEPROP 1 LAST HDL_TAP TRUE
J 0
(-6275 2850);
DISPLAY 0.872340 (-6275 2850);
DISPLAY INVISIBLE (-6275 2850);
FORCEPROP 1 LAST PATH I5
J 0
(-6602 2975);
DISPLAY 0.872340 (-6602 2975);
PAINT GREEN (-6602 2975);
DISPLAY INVISIBLE (-6602 2975);
FORCEADD TAP..1
(-6800 3425);
FORCEPROP 3 LASTPIN (-6850 3425) SIG_NAME P5E_CPU1_P3_TX_C_DN<10>
J 0
(-6840 3435);
DISPLAY 0.659574 (-6840 3435);
PAINT MONO (-6840 3435);
DISPLAY INVISIBLE (-6840 3435);
FORCEPROP 1 LASTPIN (-6850 3425) BN 10
J 0
(-6862 3433);
DISPLAY 0.680851 (-6862 3433);
PAINT GREEN (-6862 3433);
FORCEPROP 2 LAST CDS_LIB standard
J 0
(-6800 3425);
DISPLAY INVISIBLE (-6800 3425);
FORCEPROP 1 LAST BODY_TYPE PLUMBING
J 0
(-6800 3475);
DISPLAY 0.872340 (-6800 3475);
PAINT GREEN (-6800 3475);
DISPLAY INVISIBLE (-6800 3475);
FORCEPROP 1 LAST HDL_TAP TRUE
J 0
(-6475 3300);
DISPLAY 0.872340 (-6475 3300);
DISPLAY INVISIBLE (-6475 3300);
FORCEPROP 1 LAST PATH I6
J 0
(-6802 3425);
DISPLAY 0.872340 (-6802 3425);
PAINT GREEN (-6802 3425);
DISPLAY INVISIBLE (-6802 3425);
FORCEADD TAP..1
(-6600 3675);
FORCEPROP 3 LASTPIN (-6650 3675) SIG_NAME P5E_CPU1_P3_TX_C_DP<11>
J 0
(-6640 3685);
DISPLAY 0.659574 (-6640 3685);
PAINT MONO (-6640 3685);
DISPLAY INVISIBLE (-6640 3685);
FORCEPROP 1 LASTPIN (-6650 3675) BN 11
J 0
(-6662 3683);
DISPLAY 0.680851 (-6662 3683);
PAINT GREEN (-6662 3683);
FORCEPROP 2 LAST CDS_LIB standard
J 0
(-6600 3675);
DISPLAY INVISIBLE (-6600 3675);
FORCEPROP 1 LAST BODY_TYPE PLUMBING
J 0
(-6600 3725);
DISPLAY 0.872340 (-6600 3725);
PAINT GREEN (-6600 3725);
DISPLAY INVISIBLE (-6600 3725);
FORCEPROP 1 LAST HDL_TAP TRUE
J 0
(-6275 3550);
DISPLAY 0.872340 (-6275 3550);
DISPLAY INVISIBLE (-6275 3550);
FORCEPROP 1 LAST PATH I7
J 0
(-6602 3675);
DISPLAY 0.872340 (-6602 3675);
PAINT GREEN (-6602 3675);
DISPLAY INVISIBLE (-6602 3675);
FORCEADD TAP..1
(-6600 3325);
FORCEPROP 3 LASTPIN (-6650 3325) SIG_NAME P5E_CPU1_P3_TX_C_DP<10>
J 0
(-6640 3335);
DISPLAY 0.659574 (-6640 3335);
PAINT MONO (-6640 3335);
DISPLAY INVISIBLE (-6640 3335);
FORCEPROP 1 LASTPIN (-6650 3325) BN 10
J 0
(-6662 3333);
DISPLAY 0.680851 (-6662 3333);
PAINT GREEN (-6662 3333);
FORCEPROP 2 LAST CDS_LIB standard
J 0
(-6600 3325);
DISPLAY INVISIBLE (-6600 3325);
FORCEPROP 1 LAST BODY_TYPE PLUMBING
J 0
(-6600 3375);
DISPLAY 0.872340 (-6600 3375);
PAINT GREEN (-6600 3375);
DISPLAY INVISIBLE (-6600 3375);
FORCEPROP 1 LAST HDL_TAP TRUE
J 0
(-6275 3200);
DISPLAY 0.872340 (-6275 3200);
DISPLAY INVISIBLE (-6275 3200);
FORCEPROP 1 LAST PATH I8
J 0
(-6602 3325);
DISPLAY 0.872340 (-6602 3325);
PAINT GREEN (-6602 3325);
DISPLAY INVISIBLE (-6602 3325);
FORCEADD TAP..1
(-6800 3775);
FORCEPROP 3 LASTPIN (-6850 3775) SIG_NAME P5E_CPU1_P3_TX_C_DN<11>
J 0
(-6840 3785);
DISPLAY 0.659574 (-6840 3785);
PAINT MONO (-6840 3785);
DISPLAY INVISIBLE (-6840 3785);
FORCEPROP 1 LASTPIN (-6850 3775) BN 11
J 0
(-6862 3783);
DISPLAY 0.680851 (-6862 3783);
PAINT GREEN (-6862 3783);
FORCEPROP 2 LAST CDS_LIB standard
J 0
(-6800 3775);
DISPLAY INVISIBLE (-6800 3775);
FORCEPROP 1 LAST BODY_TYPE PLUMBING
J 0
(-6800 3825);
DISPLAY 0.872340 (-6800 3825);
PAINT GREEN (-6800 3825);
DISPLAY INVISIBLE (-6800 3825);
FORCEPROP 1 LAST HDL_TAP TRUE
J 0
(-6475 3650);
DISPLAY 0.872340 (-6475 3650);
DISPLAY INVISIBLE (-6475 3650);
FORCEPROP 1 LAST PATH I9
J 0
(-6802 3775);
DISPLAY 0.872340 (-6802 3775);
PAINT GREEN (-6802 3775);
DISPLAY INVISIBLE (-6802 3775);
FORCEADD QUANTA_TITLE_BLOCK_C..1
(0 0);
FORCEPROP 0 LAST CDS_CON_LAST_MODIFIED Thu Sep 14 16:12:55 2023
J 0
(-1885 15);
DISPLAY INVISIBLE (-1885 15);
FORCEPROP 1 LAST CUSTOM_TXT_CDS <CON_LAST_MODIFIED>
J 0
(-1885 15);
DISPLAY 0.978723 (-1885 15);
FORCEPROP 2 LAST CUSTOM_TXT_CDS <XR_PAGE_TITLE>
J 0
(-7890 5250);
DISPLAY 0.638298 (-7890 5250);
PAINT PINK (-7890 5250);
DISPLAY INVISIBLE (-7890 5250);
FORCEPROP 1 LAST CUSTOM_TXT_CDS <NAME_2>
J 0
(-3175 50);
FORCEPROP 1 LAST CUSTOM_TXT_CDS <NAME_1>
J 0
(-3175 175);
FORCEPROP 1 LAST CUSTOM_TXT_CDS <Q_NUMBER>
J 0
(-1403 103);
DISPLAY 1.212766 (-1403 103);
FORCEPROP 1 LAST CUSTOM_TXT_CDS <Q_PROJ>
J 0
(-2382 102);
DISPLAY 1.212766 (-2382 102);
FORCEPROP 1 LAST CUSTOM_TXT_CDS <Q_REV>
J 0
(-184 103);
DISPLAY 1.212766 (-184 103);
FORCEPROP 1 LAST CUSTOM_TXT_CDS <CON_PAGE_NUM> OF <CON_TOTAL_PAGES>
J 0
(-446 18);
DISPLAY 0.978723 (-446 18);
FORCEPROP 1 LAST Q_TITLE RETIMER_CPU1_P3(1)
J 0
(-9366 26);
DISPLAY 2.446809 (-9366 26);
PAINT GREEN (-9366 26);
FORCEPROP 2 LAST CDS_LIB pure_quanta
J 0
(0 0);
DISPLAY INVISIBLE (0 0);
FORCEPROP 1 LAST CDS_LMAN_SYM_OUTLINE -9475,6775,100,-125
J 0
(0 0);
DISPLAY 0.468085 (0 0);
PAINT GREEN (0 0);
DISPLAY INVISIBLE (0 0);
FORCEPROP 2 LAST PAGE_BORDER TRUE
J 0
(-7890 5250);
DISPLAY 0.638298 (-7890 5250);
PAINT PINK (-7890 5250);
DISPLAY INVISIBLE (-7890 5250);
FORCEPROP 2 LAST CDS_XR_PAGE_TITLE CR-350 : @T6G_MB_LIB.T6G(SCH_1):PAGE350
J 0
(-7890 5250);
DISPLAY 0.638298 (-7890 5250);
PAINT PINK (-7890 5250);
DISPLAY INVISIBLE (-7890 5250);
FORCEPROP 1 LAST Q_DEPT BU9
J 1
(-3763 49);
DISPLAY 1.957447 (-3763 49);
PAINT GREEN (-3763 49);
DISPLAY INVISIBLE (-3763 49);
FORCEPROP 1 LAST COMMENT_BODY TRUE
J 0
(12 -13);
DISPLAY 0.978723 (12 -13);
PAINT GREEN (12 -13);
DISPLAY INVISIBLE (12 -13);
WIRE 17 -1 (-6550 5100)(-5650 5100);
FORCEPROP 2 LAST SIG_NAME P5E_CPU1_P3_TX_C_DP<15:8>
J 0
(-6485 5110);
DISPLAY 0.680851 (-6485 5110);
PAINT WHITE (-6485 5110);
WIRE 17 -1 (-1925 5050)(-1925 4700);
WIRE 17 -1 (-1925 5050)(-1025 5050);
FORCEPROP 2 LAST SIG_NAME P5E_CPU1_P3_TX_C_DP<7:0>
J 0
(-1860 5060);
DISPLAY 0.680851 (-1860 5060);
PAINT WHITE (-1860 5060);
WIRE 17 -1 (-1925 4350)(-1925 4000);
WIRE 17 -1 (-1925 4700)(-1925 4350);
WIRE 17 -1 (-1925 3650)(-1925 4000);
WIRE 17 -1 (-1925 3650)(-1925 3300);
WIRE 17 -1 (-2125 2950)(-2125 2700);
WIRE 17 -1 (-2125 3400)(-2125 2950);
WIRE 17 -1 (-2125 3750)(-2125 3400);
WIRE 17 -1 (-2125 3750)(-2125 4100);
WIRE 17 -1 (-2125 4450)(-2125 4100);
WIRE 17 -1 (-2125 4800)(-2125 4450);
WIRE 17 -1 (-2125 5150)(-2125 4800);
WIRE 17 -1 (-2125 5150)(-1025 5150);
FORCEPROP 2 LAST SIG_NAME P5E_CPU1_P3_TX_C_DN<7:0>
J 0
(-1860 5160);
DISPLAY 0.680851 (-1860 5160);
PAINT WHITE (-1860 5160);
WIRE 17 -1 (-6550 4400)(-6550 4050);
WIRE 17 -1 (-6550 4850)(-6550 4400);
WIRE 17 -1 (-6550 3700)(-6550 4050);
WIRE 17 -1 (-6550 3700)(-6550 3350);
WIRE 17 -1 (-6550 5100)(-6550 4850);
WIRE 17 -1 (-6750 3800)(-6750 4150);
WIRE 17 -1 (-6750 3800)(-6750 3450);
WIRE 17 -1 (-6750 4500)(-6750 4150);
WIRE 17 -1 (-6750 4750)(-6750 4500);
WIRE 17 -1 (-6750 3450)(-6750 3100);
WIRE 17 -1 (-6750 3100)(-6750 2750);
WIRE 17 -1 (-6750 5200)(-6750 4750);
WIRE 17 -1 (-6750 5200)(-5650 5200);
FORCEPROP 2 LAST SIG_NAME P5E_CPU1_P3_TX_C_DN<15:8>
J 0
(-6485 5210);
DISPLAY 0.680851 (-6485 5210);
PAINT WHITE (-6485 5210);
WIRE 17 -1 (-6550 3350)(-6550 3000);
WIRE 17 -1 (-6550 3000)(-6550 2650);
WIRE 17 -1 (-1925 3050)(-1925 2600);
WIRE 17 -1 (-1925 3300)(-1925 3050);
WIRE 16 -1 (-2750 5125)(-2225 5125);
WIRE 16 -1 (-2750 5025)(-2025 5025);
WIRE 16 -1 (-2750 3025)(-2025 3025);
WIRE 16 -1 (-2750 3275)(-2025 3275);
WIRE 16 -1 (-7375 4825)(-6650 4825);
WIRE 16 -1 (-6850 4725)(-7375 4725);
WIRE 16 -1 (-7375 4475)(-6850 4475);
WIRE 16 -1 (-2225 2925)(-2750 2925);
WIRE 16 -1 (-2750 3625)(-2025 3625);
WIRE 16 -1 (-7375 5175)(-6850 5175);
WIRE 16 -1 (-7375 4125)(-6850 4125);
WIRE 16 -1 (-7375 2625)(-6650 2625);
WIRE 16 -1 (-7375 4375)(-6650 4375);
WIRE 16 -1 (-2750 3725)(-2225 3725);
WIRE 16 -1 (-2750 4775)(-2225 4775);
WIRE 16 -1 (-2750 4425)(-2225 4425);
WIRE 16 -1 (-2750 4325)(-2025 4325);
WIRE 16 -1 (-2750 3375)(-2225 3375);
WIRE 16 -1 (-2750 2575)(-2025 2575);
WIRE 16 -1 (-2750 4075)(-2225 4075);
WIRE 16 -1 (-7375 2725)(-6850 2725);
WIRE 16 -1 (-7375 2975)(-6650 2975);
WIRE 16 -1 (-7375 3075)(-6850 3075);
WIRE 16 -1 (-7375 3325)(-6650 3325);
WIRE 16 -1 (-7375 3425)(-6850 3425);
WIRE 16 -1 (-7375 3675)(-6650 3675);
WIRE 16 -1 (-7375 3775)(-6850 3775);
WIRE 16 -1 (-7375 4025)(-6650 4025);
WIRE 16 -1 (-2750 2675)(-2225 2675);
WIRE 16 -1 (-2750 3975)(-2025 3975);
WIRE 16 -1 (-2750 4675)(-2025 4675);
WIRE 16 -1 (-7375 5075)(-6650 5075);
FORCENOTE
P/N SWAP
(-6475 5000) 0;
DISPLAY LEFT (-6475 5000);
DISPLAY 1.021277 (-6475 5000);
FORCENOTE
P/N SWAP
(-1825 4925) 0;
DISPLAY LEFT (-1825 4925);
DISPLAY 1.021277 (-1825 4925);
FORCENOTE
P/N SWAP
(-1850 4675) 0;
DISPLAY LEFT (-1850 4675);
DISPLAY 1.021277 (-1850 4675);
FORCENOTE
P/N SWAP
(-1850 4300) 0;
DISPLAY LEFT (-1850 4300);
DISPLAY 1.021277 (-1850 4300);
FORCENOTE
P/N SWAP
(-1825 4000) 0;
DISPLAY LEFT (-1825 4000);
DISPLAY 1.021277 (-1825 4000);
FORCENOTE
P/N SWAP
(-1800 3675) 0;
DISPLAY LEFT (-1800 3675);
DISPLAY 1.021277 (-1800 3675);
FORCENOTE
P/N SWAP
(-1825 3300) 0;
DISPLAY LEFT (-1825 3300);
DISPLAY 1.021277 (-1825 3300);
FORCENOTE
P/N SWAP
(-1825 2625) 0;
DISPLAY LEFT (-1825 2625);
DISPLAY 1.021277 (-1825 2625);
FORCENOTE
P/N SWAP
(-6450 3000) 0;
DISPLAY LEFT (-6450 3000);
DISPLAY 1.021277 (-6450 3000);
FORCENOTE
P/N SWAP
(-6475 2650) 0;
DISPLAY LEFT (-6475 2650);
DISPLAY 1.021277 (-6475 2650);
FORCENOTE
P/N SWAP
(-6450 3350) 0;
DISPLAY LEFT (-6450 3350);
DISPLAY 1.021277 (-6450 3350);
FORCENOTE
P/N SWAP
(-6475 3700) 0;
DISPLAY LEFT (-6475 3700);
DISPLAY 1.021277 (-6475 3700);
FORCENOTE
P/N SWAP
(-6475 4050) 0;
DISPLAY LEFT (-6475 4050);
DISPLAY 1.021277 (-6475 4050);
FORCENOTE
P/N SWAP
(-6475 4400) 0;
DISPLAY LEFT (-6475 4400);
DISPLAY 1.021277 (-6475 4400);
FORCENOTE
CPU TO RETIMER
(-8250 1775) 0;
DISPLAY LEFT (-8250 1775);
DISPLAY 3.148936 (-8250 1775);
FORCENOTE
CPU TO RETIMER
(-3650 1775) 0;
DISPLAY LEFT (-3650 1775);
DISPLAY 3.148936 (-3650 1775);
FORCENOTE
P5E_CPU1_P3_TX_C_DP/DN<0-15> LANE REVERSAL
(-8825 6250) 0;
DISPLAY LEFT (-8825 6250);
DISPLAY 2.000000 (-8825 6250);
QUIT
